#ISCELL
  mstr_misc dns *
  *
#ISCELL
  pure_quanta quanta_title_block_c *
  *
#ISCELL
  standard offpage *
  page173_i1
#ISCELL
  standard offpage *
  page173_i10
#ISCELL
  pure_quanta_power vcc_core *
  page173_i102
#ISCELL
  pure_quanta_power vcc_core *
  page173_i104
#ISCELL
  pure_quanta_power universal_gnd *
  page173_i105
#CELL
  pure_quanta q_capp *
  page173_i106
#CELL
  pure_quanta q_capp *
  page173_i107
#CELL
  pure_quanta q_cap *
  page173_i108
#CELL
  pure_quanta q_cap *
  page173_i109
#CELL
  pure_quanta q_cap *
  page173_i110
#ISCELL
  pure_quanta_power universal_gnd *
  page173_i111
#ISCELL
  pure_quanta_power universal_gnd *
  page173_i112
#CELL
  pure_quanta q_res *
  page173_i113
#CELL
  pure_quanta q_cap *
  page173_i114
#CELL
  pure_quanta q_cap *
  page173_i116
#ISCELL
  pure_quanta_power universal_gnd *
  page173_i117
#ISCELL
  pure_quanta_power universal_gnd *
  page173_i118
#CELL
  pure_quanta q_res *
  page173_i119
#CELL
  pure_quanta q_cap *
  page173_i120
#CELL
  pure_quanta isl99390frztr5935 *
  page173_i122
#CELL
  pure_quanta isl99390frztr5935 *
  page173_i123
#ISCELL
  standard offpage *
  page173_i124
#CELL
  pure_quanta q_cap *
  page173_i125
#CELL
  pure_quanta q_res *
  page173_i126
#ISCELL
  pure_quanta_power universal_gnd *
  page173_i127
#CELL
  pure_quanta q_cap *
  page173_i128
#CELL
  pure_quanta q_res *
  page173_i129
#ISCELL
  pure_quanta_power universal_gnd *
  page173_i130
#ISCELL
  pure_quanta_power vcc_core *
  page173_i131
#ISCELL
  pure_quanta_power vcc_core *
  page173_i132
#CELL
  pure_quanta q_res *
  page173_i133
#CELL
  pure_quanta q_cap *
  page173_i134
#CELL
  pure_quanta q_cap *
  page173_i135
#ISCELL
  standard offpage *
  page173_i136
#ISCELL
  pure_quanta_power universal_gnd *
  page173_i137
#CELL
  pure_quanta q_res *
  page173_i15
#CELL
  pure_quanta q_res *
  page173_i19
#ISCELL
  pure_quanta_power universal_gnd *
  page173_i2
#CELL
  pure_quanta q_res *
  page173_i22
#CELL
  pure_quanta q_cap *
  page173_i23
#CELL
  pure_quanta q_cap *
  page173_i24
#CELL
  pure_quanta q_cap *
  page173_i25
#CELL
  pure_quanta q_cap *
  page173_i26
#CELL
  pure_quanta q_cap *
  page173_i29
#ISCELL
  standard offpage *
  page173_i3
#ISCELL
  pure_quanta_power universal_gnd *
  page173_i31
#CELL
  pure_quanta q_inductor *
  page173_i34
#ISCELL
  pure_quanta_power vcc_core *
  page173_i35
#CELL
  pure_quanta q_cap *
  page173_i37
#ISCELL
  pure_quanta_power universal_gnd *
  page173_i38
#CELL
  pure_quanta q_cap *
  page173_i39
#CELL
  pure_quanta q_cap *
  page173_i4
#ISCELL
  pure_quanta_power vcc_core *
  page173_i40
#CELL
  pure_quanta q_inductor4p_14 *
  page173_i42
#CELL
  pure_quanta q_cap *
  page173_i43
#ISCELL
  standard offpage *
  page173_i45
#ISCELL
  pure_quanta_power universal_gnd *
  page173_i46
#ISCELL
  standard offpage *
  page173_i47
#CELL
  pure_quanta q_cap *
  page173_i48
#ISCELL
  pure_quanta_power universal_gnd *
  page173_i49
#ISCELL
  pure_quanta_power universal_gnd *
  page173_i5
#ISCELL
  pure_quanta_power universal_gnd *
  page173_i50
#ISCELL
  standard offpage *
  page173_i51
#CELL
  pure_quanta q_res *
  page173_i52
#ISCELL
  standard offpage *
  page173_i55
#ISCELL
  pure_quanta_power universal_gnd *
  page173_i6
#CELL
  pure_quanta q_res *
  page173_i63
#CELL
  pure_quanta q_res *
  page173_i65
#CELL
  pure_quanta q_cap *
  page173_i66
#CELL
  pure_quanta q_cap *
  page173_i67
#CELL
  pure_quanta q_cap *
  page173_i68
#CELL
  pure_quanta q_cap *
  page173_i69
#ISCELL
  standard offpage *
  page173_i7
#CELL
  pure_quanta q_cap *
  page173_i70
#ISCELL
  pure_quanta_power universal_gnd *
  page173_i71
#ISCELL
  pure_quanta_power vcc_core *
  page173_i73
#CELL
  pure_quanta q_cap *
  page173_i79
#ISCELL
  pure_quanta_power universal_gnd *
  page173_i80
#CELL
  pure_quanta q_cap *
  page173_i81
#ISCELL
  pure_quanta_power vcc_core *
  page173_i82
#CELL
  pure_quanta q_inductor4p_14 *
  page173_i83
#ISCELL
  standard offpage *
  page173_i86
#CELL
  pure_quanta q_capp *
  page173_i92
#CELL
  pure_quanta q_capp *
  page173_i94
